(kicad_pcb
	(version 20260206)
	(generator "pcbnew")
	(generator_version "10.0")
	(general
		(thickness 1.6)
		(legacy_teardrops no)
	)
	(paper "A4")
	(title_block
		(title "04192023_DAF0TMB3IC0_F0TG_MB_C_brd_V02_OCP.brd")
		(comment 1 "Grand Teton / footprint 2783 of 8354 (U26), pads 5671-5779 of 6102")
	)
	(layers
		(0 "F.Cu" signal "TOP")
		(4 "In1.Cu" signal "GND")
		(6 "In2.Cu" signal "IN1")
		(8 "In3.Cu" signal "GND1")
		(10 "In4.Cu" signal "IN2")
		(12 "In5.Cu" signal "GND2")
		(14 "In6.Cu" signal "IN3")
		(16 "In7.Cu" signal "GND3")
		(18 "In8.Cu" signal "VCC")
		(20 "In9.Cu" signal "VCC1")
		(22 "In10.Cu" signal "GND4")
		(24 "In11.Cu" signal "IN4")
		(26 "In12.Cu" signal "GND5")
		(28 "In13.Cu" signal "IN5")
		(30 "In14.Cu" signal "GND6")
		(32 "In15.Cu" signal "IN6")
		(34 "In16.Cu" signal "GND7")
		(2 "B.Cu" signal "BOTTOM")
		(9 "F.Adhes" user "F.Adhesive")
		(11 "B.Adhes" user "B.Adhesive")
		(13 "F.Paste" user "Package Geometry/Pastemask Top")
		(15 "B.Paste" user "Package Geometry/Pastemask Bottom")
		(5 "F.SilkS" user "Ref Des/Silkscreen Top")
		(7 "B.SilkS" user "Ref Des/Silkscreen Bottom")
		(1 "F.Mask" user "Board Geometry/Soldermask Top")
		(3 "B.Mask" user "Board Geometry/Soldermask Bottom")
		(17 "Dwgs.User" user "User.Drawings")
		(19 "Cmts.User" user "User.Comments")
		(21 "Eco1.User" user "User.Eco1")
		(23 "Eco2.User" user "User.Eco2")
		(25 "Edge.Cuts" user "Board Geometry/Outline")
		(27 "Margin" user)
		(31 "F.CrtYd" user "Package Geometry/Place Bound Top")
		(29 "B.CrtYd" user "Package Geometry/Place Bound Bottom")
		(35 "F.Fab" user "Ref Des/Assembly Top")
		(33 "B.Fab" user "Ref Des/Assembly Bottom")
	)
	(footprint ""
		(layer "F.Cu")
		(at 111.927894 -258.880356 180)
		(property "Reference" "U26"
			(at -45.05579 -61.794136 0)
			(unlocked yes)
			(layer "F.SilkS")
			(effects
				(font
					(size 0.7874 0.5842)
					(thickness 0.1524)
				)
			)
		)
		(property "Value" ""
			(at 0 0 180)
			(layer "F.Fab")
			(effects
				(font
					(size 1.27 1.27)
				)
			)
		)
		(duplicate_pad_numbers_are_jumpers no)
		(pad "R1" smd circle
			(at -34.159952 -25.470104 180)
			(size 0.450088 0.450088)
			(layers "F.Cu" "F.Mask" "F.Paste")
			(net "GND")
		)
		(pad "R2" smd circle
			(at -33.219898 -25.470104 180)
			(size 0.450088 0.450088)
			(layers "F.Cu" "F.Mask" "F.Paste")
			(net "M_G_CPU1_SA_DQ<12>")
		)
		(pad "R3" smd circle
			(at -32.280098 -25.470104 180)
			(size 0.450088 0.450088)
			(layers "F.Cu" "F.Mask" "F.Paste")
			(net "M_G_CPU1_SA_DQS_DP<6>")
		)
		(pad "R4" smd circle
			(at -31.340044 -25.470104 180)
			(size 0.450088 0.450088)
			(layers "F.Cu" "F.Mask" "F.Paste")
			(net "GND")
		)
		(pad "R5" smd circle
			(at -30.39999 -25.470104 180)
			(size 0.450088 0.450088)
			(layers "F.Cu" "F.Mask" "F.Paste")
			(net "M_K_CPU1_SA_DQ<12>")
		)
		(pad "R6" smd circle
			(at -29.459936 -25.470104 180)
			(size 0.450088 0.450088)
			(layers "F.Cu" "F.Mask" "F.Paste")
			(net "GND")
		)
		(pad "R7" smd circle
			(at -28.519882 -25.470104 180)
			(size 0.450088 0.450088)
			(layers "F.Cu" "F.Mask" "F.Paste")
			(net "M_K_CPU1_SA_DQS_DP<6>")
		)
		(pad "R8" smd circle
			(at -27.580082 -25.470104 180)
			(size 0.450088 0.450088)
			(layers "F.Cu" "F.Mask" "F.Paste")
			(net "GND")
		)
		(pad "R9" smd circle
			(at -26.640028 -25.470104 180)
			(size 0.450088 0.450088)
			(layers "F.Cu" "F.Mask" "F.Paste")
			(net "M_L_CPU1_SA_DQ<12>")
		)
		(pad "R10" smd circle
			(at -25.699974 -25.470104 180)
			(size 0.450088 0.450088)
			(layers "F.Cu" "F.Mask" "F.Paste")
			(net "M_L_CPU1_SA_DQS_DP<6>")
		)
		(pad "R11" smd circle
			(at -24.75992 -25.470104 180)
			(size 0.450088 0.450088)
			(layers "F.Cu" "F.Mask" "F.Paste")
			(net "GND")
		)
		(pad "R12" smd circle
			(at -23.82012 -25.470104 180)
			(size 0.450088 0.450088)
			(layers "F.Cu" "F.Mask" "F.Paste")
			(net "M_H_CPU1_SA_DQ<12>")
		)
		(pad "R13" smd circle
			(at -22.880066 -25.470104 180)
			(size 0.450088 0.450088)
			(layers "F.Cu" "F.Mask" "F.Paste")
			(net "GND")
		)
		(pad "R14" smd circle
			(at -21.940012 -25.470104 180)
			(size 0.450088 0.450088)
			(layers "F.Cu" "F.Mask" "F.Paste")
			(net "M_H_CPU1_SA_DQS_DP<6>")
		)
		(pad "R15" smd circle
			(at -20.999958 -25.470104 180)
			(size 0.450088 0.450088)
			(layers "F.Cu" "F.Mask" "F.Paste")
			(net "GND")
		)
		(pad "R16" smd circle
			(at -20.059904 -25.470104 180)
			(size 0.450088 0.450088)
			(layers "F.Cu" "F.Mask" "F.Paste")
			(net "M_J_CPU1_SA_DQ<12>")
		)
		(pad "R17" smd circle
			(at -19.120104 -25.470104 180)
			(size 0.450088 0.450088)
			(layers "F.Cu" "F.Mask" "F.Paste")
			(net "M_J_CPU1_SA_DQS_DP<6>")
		)
		(pad "R18" smd circle
			(at -18.18005 -25.470104 180)
			(size 0.450088 0.450088)
			(layers "F.Cu" "F.Mask" "F.Paste")
			(net "GND")
		)
		(pad "R19" smd circle
			(at -17.239996 -25.470104 180)
			(size 0.450088 0.450088)
			(layers "F.Cu" "F.Mask" "F.Paste")
			(net "M_I_CPU1_SA_DQ<12>")
		)
		(pad "R20" smd circle
			(at -16.299942 -25.470104 180)
			(size 0.450088 0.450088)
			(layers "F.Cu" "F.Mask" "F.Paste")
			(net "GND")
		)
		(pad "R21" smd circle
			(at -15.359888 -25.470104 180)
			(size 0.450088 0.450088)
			(layers "F.Cu" "F.Mask" "F.Paste")
			(net "M_I_CPU1_SA_DQS_DP<6>")
		)
		(pad "R22" smd circle
			(at -14.420088 -25.470104 180)
			(size 0.450088 0.450088)
			(layers "F.Cu" "F.Mask" "F.Paste")
			(net "GND")
		)
		(pad "R23" smd circle
			(at -13.480034 -25.470104 180)
			(size 0.450088 0.450088)
			(layers "F.Cu" "F.Mask" "F.Paste")
			(net "GMI_CPU1_G3_CPU0_G1_TX_DP<14>")
		)
		(pad "R24" smd circle
			(at -12.53998 -25.470104 180)
			(size 0.450088 0.450088)
			(layers "F.Cu" "F.Mask" "F.Paste")
			(net "GMI_CPU1_G3_CPU0_G1_TX_DN<14>")
		)
		(pad "R25" smd circle
			(at -11.599926 -25.470104 180)
			(size 0.450088 0.450088)
			(layers "F.Cu" "F.Mask" "F.Paste")
			(net "GND")
		)
		(pad "R26" smd circle
			(at -10.659872 -25.470104 180)
			(size 0.450088 0.450088)
			(layers "F.Cu" "F.Mask" "F.Paste")
			(net "GMI_CPU1_G3_CPU0_G1_TX_DP<11>")
		)
		(pad "R27" smd circle
			(at -9.720072 -25.470104 180)
			(size 0.450088 0.450088)
			(layers "F.Cu" "F.Mask" "F.Paste")
			(net "GMI_CPU1_G3_CPU0_G1_TX_DN<11>")
		)
		(pad "R28" smd circle
			(at -8.780018 -25.470104 180)
			(size 0.450088 0.450088)
			(layers "F.Cu" "F.Mask" "F.Paste")
			(net "GND")
		)
		(pad "R29" smd circle
			(at -7.839964 -25.470104 180)
			(size 0.450088 0.450088)
			(layers "F.Cu" "F.Mask" "F.Paste")
			(net "GMI_CPU1_G3_CPU0_G1_TX_DP<8>")
		)
		(pad "R30" smd circle
			(at -6.89991 -25.470104 180)
			(size 0.450088 0.450088)
			(layers "F.Cu" "F.Mask" "F.Paste")
			(net "GMI_CPU1_G3_CPU0_G1_TX_DN<8>")
		)
		(pad "R31" smd circle
			(at -5.96011 -25.470104 180)
			(size 0.450088 0.450088)
			(layers "F.Cu" "F.Mask" "F.Paste")
			(net "GND")
		)
		(pad "R32" smd circle
			(at -5.020056 -25.470104 180)
			(size 0.450088 0.450088)
			(layers "F.Cu" "F.Mask" "F.Paste")
			(net "GMI_CPU1_G3_CPU0_G1_TX_DP<5>")
		)
		(pad "R33" smd circle
			(at -4.080002 -25.470104 180)
			(size 0.450088 0.450088)
			(layers "F.Cu" "F.Mask" "F.Paste")
			(net "GMI_CPU1_G3_CPU0_G1_TX_DN<5>")
		)
		(pad "R34" smd circle
			(at -3.139948 -25.470104 180)
			(size 0.450088 0.450088)
			(layers "F.Cu" "F.Mask" "F.Paste")
			(net "GND")
		)
		(pad "R35" smd circle
			(at -2.199894 -25.470104 180)
			(size 0.450088 0.450088)
			(layers "F.Cu" "F.Mask" "F.Paste")
			(net "GND")
		)
		(pad "R36" smd circle
			(at -1.260094 -25.470104 180)
			(size 0.450088 0.450088)
			(layers "F.Cu" "F.Mask" "F.Paste")
			(net "GND")
		)
		(pad "R40" smd circle
			(at 1.560068 -25.470104 180)
			(size 0.450088 0.450088)
			(layers "F.Cu" "F.Mask" "F.Paste")
			(net "GND")
		)
		(pad "R41" smd circle
			(at 2.500122 -25.470104 180)
			(size 0.450088 0.450088)
			(layers "F.Cu" "F.Mask" "F.Paste")
			(net "GND")
		)
		(pad "R42" smd circle
			(at 3.439922 -25.470104 180)
			(size 0.450088 0.450088)
			(layers "F.Cu" "F.Mask" "F.Paste")
			(net "GND")
		)
		(pad "R43" smd circle
			(at 4.379976 -25.470104 180)
			(size 0.450088 0.450088)
			(layers "F.Cu" "F.Mask" "F.Paste")
			(net "P5E_CPU1_G1_RX_DN<5>")
		)
		(pad "R44" smd circle
			(at 5.32003 -25.470104 180)
			(size 0.450088 0.450088)
			(layers "F.Cu" "F.Mask" "F.Paste")
			(net "P5E_CPU1_G1_RX_DP<5>")
		)
		(pad "R45" smd circle
			(at 6.260084 -25.470104 180)
			(size 0.450088 0.450088)
			(layers "F.Cu" "F.Mask" "F.Paste")
			(net "GND")
		)
		(pad "R46" smd circle
			(at 7.199884 -25.470104 180)
			(size 0.450088 0.450088)
			(layers "F.Cu" "F.Mask" "F.Paste")
			(net "P5E_CPU1_G1_RX_DN<8>")
		)
		(pad "R47" smd circle
			(at 8.139938 -25.470104 180)
			(size 0.450088 0.450088)
			(layers "F.Cu" "F.Mask" "F.Paste")
			(net "P5E_CPU1_G1_RX_DP<8>")
		)
		(pad "R48" smd circle
			(at 9.079992 -25.470104 180)
			(size 0.450088 0.450088)
			(layers "F.Cu" "F.Mask" "F.Paste")
			(net "GND")
		)
		(pad "R49" smd circle
			(at 10.020046 -25.470104 180)
			(size 0.450088 0.450088)
			(layers "F.Cu" "F.Mask" "F.Paste")
			(net "P5E_CPU1_G1_RX_DN<11>")
		)
		(pad "R50" smd circle
			(at 10.9601 -25.470104 180)
			(size 0.450088 0.450088)
			(layers "F.Cu" "F.Mask" "F.Paste")
			(net "P5E_CPU1_G1_RX_DP<11>")
		)
		(pad "R51" smd circle
			(at 11.8999 -25.470104 180)
			(size 0.450088 0.450088)
			(layers "F.Cu" "F.Mask" "F.Paste")
			(net "GND")
		)
		(pad "R52" smd circle
			(at 12.839954 -25.470104 180)
			(size 0.450088 0.450088)
			(layers "F.Cu" "F.Mask" "F.Paste")
			(net "P5E_CPU1_G1_RX_DN<14>")
		)
		(pad "R53" smd circle
			(at 13.780008 -25.470104 180)
			(size 0.450088 0.450088)
			(layers "F.Cu" "F.Mask" "F.Paste")
			(net "P5E_CPU1_G1_RX_DP<14>")
		)
		(pad "R54" smd circle
			(at 14.720062 -25.470104 180)
			(size 0.450088 0.450088)
			(layers "F.Cu" "F.Mask" "F.Paste")
			(net "GND")
		)
		(pad "R55" smd circle
			(at 15.660116 -25.470104 180)
			(size 0.450088 0.450088)
			(layers "F.Cu" "F.Mask" "F.Paste")
			(net "M_C_CPU1_SA_DQS_DP<6>")
		)
		(pad "R56" smd circle
			(at 16.599916 -25.470104 180)
			(size 0.450088 0.450088)
			(layers "F.Cu" "F.Mask" "F.Paste")
			(net "GND")
		)
		(pad "R57" smd circle
			(at 17.53997 -25.470104 180)
			(size 0.450088 0.450088)
			(layers "F.Cu" "F.Mask" "F.Paste")
			(net "M_C_CPU1_SA_DQ<12>")
		)
		(pad "R58" smd circle
			(at 18.480024 -25.470104 180)
			(size 0.450088 0.450088)
			(layers "F.Cu" "F.Mask" "F.Paste")
			(net "GND")
		)
		(pad "R59" smd circle
			(at 19.420078 -25.470104 180)
			(size 0.450088 0.450088)
			(layers "F.Cu" "F.Mask" "F.Paste")
			(net "M_D_CPU1_SA_DQS_DP<6>")
		)
		(pad "R60" smd circle
			(at 20.359878 -25.470104 180)
			(size 0.450088 0.450088)
			(layers "F.Cu" "F.Mask" "F.Paste")
			(net "M_D_CPU1_SA_DQ<12>")
		)
		(pad "R61" smd circle
			(at 21.299932 -25.470104 180)
			(size 0.450088 0.450088)
			(layers "F.Cu" "F.Mask" "F.Paste")
			(net "GND")
		)
		(pad "R62" smd circle
			(at 22.239986 -25.470104 180)
			(size 0.450088 0.450088)
			(layers "F.Cu" "F.Mask" "F.Paste")
			(net "M_B_CPU1_SA_DQS_DP<6>")
		)
		(pad "R63" smd circle
			(at 23.18004 -25.470104 180)
			(size 0.450088 0.450088)
			(layers "F.Cu" "F.Mask" "F.Paste")
			(net "GND")
		)
		(pad "R64" smd circle
			(at 24.120094 -25.470104 180)
			(size 0.450088 0.450088)
			(layers "F.Cu" "F.Mask" "F.Paste")
			(net "M_B_CPU1_SA_DQ<12>")
		)
		(pad "R65" smd circle
			(at 25.059894 -25.470104 180)
			(size 0.450088 0.450088)
			(layers "F.Cu" "F.Mask" "F.Paste")
			(net "GND")
		)
		(pad "R66" smd circle
			(at 25.999948 -25.470104 180)
			(size 0.450088 0.450088)
			(layers "F.Cu" "F.Mask" "F.Paste")
			(net "M_F_CPU1_SA_DQS_DP<6>")
		)
		(pad "R67" smd circle
			(at 26.940002 -25.470104 180)
			(size 0.450088 0.450088)
			(layers "F.Cu" "F.Mask" "F.Paste")
			(net "M_F_CPU1_SA_DQ<12>")
		)
		(pad "R68" smd circle
			(at 27.880056 -25.470104 180)
			(size 0.450088 0.450088)
			(layers "F.Cu" "F.Mask" "F.Paste")
			(net "GND")
		)
		(pad "R69" smd circle
			(at 28.82011 -25.470104 180)
			(size 0.450088 0.450088)
			(layers "F.Cu" "F.Mask" "F.Paste")
			(net "M_E_CPU1_SA_DQS_DP<6>")
		)
		(pad "R70" smd circle
			(at 29.75991 -25.470104 180)
			(size 0.450088 0.450088)
			(layers "F.Cu" "F.Mask" "F.Paste")
			(net "GND")
		)
		(pad "R71" smd circle
			(at 30.699964 -25.470104 180)
			(size 0.450088 0.450088)
			(layers "F.Cu" "F.Mask" "F.Paste")
			(net "M_E_CPU1_SA_DQ<12>")
		)
		(pad "R72" smd circle
			(at 31.640018 -25.470104 180)
			(size 0.450088 0.450088)
			(layers "F.Cu" "F.Mask" "F.Paste")
			(net "GND")
		)
		(pad "R73" smd circle
			(at 32.580072 -25.470104 180)
			(size 0.450088 0.450088)
			(layers "F.Cu" "F.Mask" "F.Paste")
			(net "M_A_CPU1_SA_DQS_DP<6>")
		)
		(pad "R74" smd circle
			(at 33.519872 -25.470104 180)
			(size 0.450088 0.450088)
			(layers "F.Cu" "F.Mask" "F.Paste")
			(net "M_A_CPU1_SA_DQ<12>")
		)
		(pad "R75" smd circle
			(at 34.459926 -25.470104 180)
			(size 0.450088 0.450088)
			(layers "F.Cu" "F.Mask" "F.Paste")
			(net "GND")
		)
		(pad "T2" smd circle
			(at -33.690052 -24.660098 180)
			(size 0.450088 0.450088)
			(layers "F.Cu" "F.Mask" "F.Paste")
			(net "M_G_CPU1_SA_DQ<14>")
		)
		(pad "T3" smd circle
			(at -32.749998 -24.660098 180)
			(size 0.450088 0.450088)
			(layers "F.Cu" "F.Mask" "F.Paste")
			(net "GND")
		)
		(pad "T4" smd circle
			(at -31.809944 -24.660098 180)
			(size 0.450088 0.450088)
			(layers "F.Cu" "F.Mask" "F.Paste")
			(net "M_G_CPU1_SA_DQ<13>")
		)
		(pad "T5" smd circle
			(at -30.86989 -24.660098 180)
			(size 0.450088 0.450088)
			(layers "F.Cu" "F.Mask" "F.Paste")
			(net "GND")
		)
		(pad "T6" smd circle
			(at -29.93009 -24.660098 180)
			(size 0.450088 0.450088)
			(layers "F.Cu" "F.Mask" "F.Paste")
			(net "M_K_CPU1_SA_DQ<14>")
		)
		(pad "T7" smd circle
			(at -28.990036 -24.660098 180)
			(size 0.450088 0.450088)
			(layers "F.Cu" "F.Mask" "F.Paste")
			(net "M_K_CPU1_SA_DQ<13>")
		)
		(pad "T8" smd circle
			(at -28.049982 -24.660098 180)
			(size 0.450088 0.450088)
			(layers "F.Cu" "F.Mask" "F.Paste")
			(net "GND")
		)
		(pad "T9" smd circle
			(at -27.109928 -24.660098 180)
			(size 0.450088 0.450088)
			(layers "F.Cu" "F.Mask" "F.Paste")
			(net "M_L_CPU1_SA_DQ<14>")
		)
		(pad "T10" smd circle
			(at -26.170128 -24.660098 180)
			(size 0.450088 0.450088)
			(layers "F.Cu" "F.Mask" "F.Paste")
			(net "GND")
		)
		(pad "T11" smd circle
			(at -25.230074 -24.660098 180)
			(size 0.450088 0.450088)
			(layers "F.Cu" "F.Mask" "F.Paste")
			(net "M_L_CPU1_SA_DQ<13>")
		)
		(pad "T12" smd circle
			(at -24.29002 -24.660098 180)
			(size 0.450088 0.450088)
			(layers "F.Cu" "F.Mask" "F.Paste")
			(net "GND")
		)
		(pad "T13" smd circle
			(at -23.349966 -24.660098 180)
			(size 0.450088 0.450088)
			(layers "F.Cu" "F.Mask" "F.Paste")
			(net "M_H_CPU1_SA_DQ<14>")
		)
		(pad "T14" smd circle
			(at -22.409912 -24.660098 180)
			(size 0.450088 0.450088)
			(layers "F.Cu" "F.Mask" "F.Paste")
			(net "M_H_CPU1_SA_DQ<13>")
		)
		(pad "T15" smd circle
			(at -21.470112 -24.660098 180)
			(size 0.450088 0.450088)
			(layers "F.Cu" "F.Mask" "F.Paste")
			(net "GND")
		)
		(pad "T16" smd circle
			(at -20.530058 -24.660098 180)
			(size 0.450088 0.450088)
			(layers "F.Cu" "F.Mask" "F.Paste")
			(net "M_J_CPU1_SA_DQ<14>")
		)
		(pad "T17" smd circle
			(at -19.590004 -24.660098 180)
			(size 0.450088 0.450088)
			(layers "F.Cu" "F.Mask" "F.Paste")
			(net "GND")
		)
		(pad "T18" smd circle
			(at -18.64995 -24.660098 180)
			(size 0.450088 0.450088)
			(layers "F.Cu" "F.Mask" "F.Paste")
			(net "M_J_CPU1_SA_DQ<13>")
		)
		(pad "T19" smd circle
			(at -17.709896 -24.660098 180)
			(size 0.450088 0.450088)
			(layers "F.Cu" "F.Mask" "F.Paste")
			(net "GND")
		)
		(pad "T20" smd circle
			(at -16.770096 -24.660098 180)
			(size 0.450088 0.450088)
			(layers "F.Cu" "F.Mask" "F.Paste")
			(net "M_I_CPU1_SA_DQ<14>")
		)
		(pad "T21" smd circle
			(at -15.830042 -24.660098 180)
			(size 0.450088 0.450088)
			(layers "F.Cu" "F.Mask" "F.Paste")
			(net "M_I_CPU1_SA_DQ<13>")
		)
		(pad "T22" smd circle
			(at -14.889988 -24.660098 180)
			(size 0.450088 0.450088)
			(layers "F.Cu" "F.Mask" "F.Paste")
			(net "GND")
		)
		(pad "T23" smd circle
			(at -13.949934 -24.660098 180)
			(size 0.450088 0.450088)
			(layers "F.Cu" "F.Mask" "F.Paste")
			(net "PVDDCR_CPU0_P1")
		)
		(pad "T24" smd circle
			(at -13.00988 -24.660098 180)
			(size 0.450088 0.450088)
			(layers "F.Cu" "F.Mask" "F.Paste")
			(net "PVDDCR_CPU0_P1")
		)
		(pad "T25" smd circle
			(at -12.07008 -24.660098 180)
			(size 0.450088 0.450088)
			(layers "F.Cu" "F.Mask" "F.Paste")
			(net "GND")
		)
		(pad "T26" smd circle
			(at -11.130026 -24.660098 180)
			(size 0.450088 0.450088)
			(layers "F.Cu" "F.Mask" "F.Paste")
			(net "PVDDCR_CPU0_P1")
		)
		(pad "T27" smd circle
			(at -10.189972 -24.660098 180)
			(size 0.450088 0.450088)
			(layers "F.Cu" "F.Mask" "F.Paste")
			(net "PVDDCR_CPU0_P1")
		)
		(pad "T28" smd circle
			(at -9.249918 -24.660098 180)
			(size 0.450088 0.450088)
			(layers "F.Cu" "F.Mask" "F.Paste")
			(net "GND")
		)
		(pad "T29" smd circle
			(at -8.310118 -24.660098 180)
			(size 0.450088 0.450088)
			(layers "F.Cu" "F.Mask" "F.Paste")
			(net "PVDDCR_CPU0_P1")
		)
		(pad "T30" smd circle
			(at -7.370064 -24.660098 180)
			(size 0.450088 0.450088)
			(layers "F.Cu" "F.Mask" "F.Paste")
			(net "PVDDCR_CPU0_P1")
		)
		(pad "T31" smd circle
			(at -6.43001 -24.660098 180)
			(size 0.450088 0.450088)
			(layers "F.Cu" "F.Mask" "F.Paste")
			(net "GND")
		)
		(pad "T32" smd circle
			(at -5.489956 -24.660098 180)
			(size 0.450088 0.450088)
			(layers "F.Cu" "F.Mask" "F.Paste")
			(net "PVDDCR_CPU0_P1")
		)
		(pad "T33" smd circle
			(at -4.549902 -24.660098 180)
			(size 0.450088 0.450088)
			(layers "F.Cu" "F.Mask" "F.Paste")
			(net "PVDDCR_CPU0_P1")
		)
		(pad "T34" smd circle
			(at -3.610102 -24.660098 180)
			(size 0.450088 0.450088)
			(layers "F.Cu" "F.Mask" "F.Paste")
			(net "GND")
		)
		(pad "T35" smd circle
			(at -2.670048 -24.660098 180)
			(size 0.450088 0.450088)
			(layers "F.Cu" "F.Mask" "F.Paste")
			(net "GMI_CPU1_G3_CPU0_G1_TX_DP<1>")
		)
		(pad "T36" smd circle
			(at -1.729994 -24.660098 180)
			(size 0.450088 0.450088)
			(layers "F.Cu" "F.Mask" "F.Paste")
			(net "GMI_CPU1_G3_CPU0_G1_TX_DN<1>")
		)
		(pad "T37" smd circle
			(at -0.78994 -24.660098 180)
			(size 0.450088 0.450088)
			(layers "F.Cu" "F.Mask" "F.Paste")
			(net "GND")
		)
		(pad "T39" smd circle
			(at 1.089914 -24.660098 180)
			(size 0.450088 0.450088)
			(layers "F.Cu" "F.Mask" "F.Paste")
			(net "GND")
		)
	)
)
